# S9S_MB_2U (Grand Teton) — schematic netlist excerpt (pin names and nets, part order shuffled) for the footprints in the layout excerpt that follows; sources: Cadence DE-HDL packaged netlist, KiCad conversion of 03242023_DA0F0TMBIJ0_F0T_Motherboard_J_brd_V01_OCP.brd

R310  Q_RES  150 1% CHIP  pkg 0402LF  page 284 : A = SVID_CLK0_CPU1_R ; B = SVID_CLK_PVCCIN_CPU1_R
PL170  Q_INDUCTOR  2.2UH IND  pkg SMLF  page 263 : \1\ = SW_P1V8_PCH_AUX_SW ; \2\ = P1V8_PCH_AUX
PC632  Q_CAP  1UF 16V 10% X6S  pkg C0402  page 278 : A = PVCCD_HV_CPU0_VCC ; B = GND

(kicad_pcb
	(version 20260206)
	(generator "pcbnew")
	(generator_version "10.0")
	(general
		(thickness 1.6)
		(legacy_teardrops no)
	)
	(paper "A4")
	(title_block
		(title "03242023_DA0F0TMBIJ0_F0T_Motherboard_J_brd_V01_OCP.brd")
		(comment 1 "Grand Teton / footprints 616-618 of 6105")
	)
	(layers
		(0 "F.Cu" signal "TOP")
		(4 "In1.Cu" signal "GND")
		(6 "In2.Cu" signal "IN1")
		(8 "In3.Cu" signal "GND1")
		(10 "In4.Cu" signal "IN2")
		(12 "In5.Cu" signal "GND2")
		(14 "In6.Cu" signal "IN3")
		(16 "In7.Cu" signal "GND3")
		(18 "In8.Cu" signal "VCC")
		(20 "In9.Cu" signal "VCC1")
		(22 "In10.Cu" signal "GND4")
		(24 "In11.Cu" signal "IN4")
		(26 "In12.Cu" signal "GND5")
		(28 "In13.Cu" signal "IN5")
		(30 "In14.Cu" signal "GND6")
		(32 "In15.Cu" signal "IN6")
		(34 "In16.Cu" signal "GND7")
		(2 "B.Cu" signal "BOTTOM")
		(9 "F.Adhes" user "F.Adhesive")
		(11 "B.Adhes" user "B.Adhesive")
		(13 "F.Paste" user "Package Geometry/Pastemask Top")
		(15 "B.Paste" user "Package Geometry/Pastemask Bottom")
		(5 "F.SilkS" user "Ref Des/Silkscreen Top")
		(7 "B.SilkS" user "Ref Des/Silkscreen Bottom")
		(1 "F.Mask" user "Board Geometry/Soldermask Top")
		(3 "B.Mask" user "Board Geometry/Soldermask Bottom")
		(17 "Dwgs.User" user "User.Drawings")
		(19 "Cmts.User" user "User.Comments")
		(21 "Eco1.User" user "User.Eco1")
		(23 "Eco2.User" user "User.Eco2")
		(25 "Edge.Cuts" user "Board Geometry/Outline")
		(27 "Margin" user)
		(31 "F.CrtYd" user "Package Geometry/Place Bound Top")
		(29 "B.CrtYd" user "Package Geometry/Place Bound Bottom")
		(35 "F.Fab" user "Ref Des/Assembly Top")
		(33 "B.Fab" user "Ref Des/Assembly Bottom")
	)
	(footprint ""
		(layer "F.Cu")
		(at 428.62373 -119.349012 180)
		(property "Reference" "PC632"
			(at 0 0 180)
			(layer "F.SilkS")
			(hide yes)
			(effects
				(font
					(size 1.27 1.27)
				)
			)
		)
		(property "Value" ""
			(at 0 0 180)
			(layer "F.Fab")
			(effects
				(font
					(size 1.27 1.27)
				)
			)
		)
		(duplicate_pad_numbers_are_jumpers no)
		(fp_line
			(start 0.7874 0.4064)
			(end -0.7874 0.4064)
			(stroke
				(width 0.1524)
				(type default)
			)
			(layer "F.SilkS")
		)
		(fp_line
			(start 0.7874 -0.4064)
			(end 0.7874 0.4064)
			(stroke
				(width 0.1524)
				(type default)
			)
			(layer "F.SilkS")
		)
		(fp_line
			(start -0.7874 0.4064)
			(end -0.7874 -0.4064)
			(stroke
				(width 0.1524)
				(type default)
			)
			(layer "F.SilkS")
		)
		(fp_line
			(start -0.7874 -0.4064)
			(end 0.7874 -0.4064)
			(stroke
				(width 0.1524)
				(type default)
			)
			(layer "F.SilkS")
		)
		(fp_line
			(start 0.67945 0.3048)
			(end 0.120396 0.3048)
			(stroke
				(width 0.1)
				(type default)
			)
			(layer "F.Fab")
		)
		(fp_line
			(start 0.67945 -0.3048)
			(end 0.67945 0.3048)
			(stroke
				(width 0.1)
				(type default)
			)
			(layer "F.Fab")
		)
		(fp_line
			(start 0.12065 -0.2794)
			(end 0.12065 -0.3048)
			(stroke
				(width 0.1)
				(type default)
			)
			(layer "F.Fab")
		)
		(fp_line
			(start 0.12065 -0.3048)
			(end 0.67945 -0.3048)
			(stroke
				(width 0.1)
				(type default)
			)
			(layer "F.Fab")
		)
		(fp_line
			(start 0.120396 0.3048)
			(end 0.120396 0.2794)
			(stroke
				(width 0.1)
				(type default)
			)
			(layer "F.Fab")
		)
		(fp_line
			(start 0.120396 0.2794)
			(end -0.12065 0.2794)
			(stroke
				(width 0.1)
				(type default)
			)
			(layer "F.Fab")
		)
		(fp_line
			(start -0.12065 0.3048)
			(end -0.67945 0.3048)
			(stroke
				(width 0.1)
				(type default)
			)
			(layer "F.Fab")
		)
		(fp_line
			(start -0.12065 0.2794)
			(end -0.12065 0.3048)
			(stroke
				(width 0.1)
				(type default)
			)
			(layer "F.Fab")
		)
		(fp_line
			(start -0.12065 -0.2794)
			(end 0.12065 -0.2794)
			(stroke
				(width 0.1)
				(type default)
			)
			(layer "F.Fab")
		)
		(fp_line
			(start -0.12065 -0.305054)
			(end -0.12065 -0.2794)
			(stroke
				(width 0.1)
				(type default)
			)
			(layer "F.Fab")
		)
		(fp_line
			(start -0.67945 0.3048)
			(end -0.67945 -0.305054)
			(stroke
				(width 0.1)
				(type default)
			)
			(layer "F.Fab")
		)
		(fp_line
			(start -0.67945 -0.305054)
			(end -0.12065 -0.305054)
			(stroke
				(width 0.1)
				(type default)
			)
			(layer "F.Fab")
		)
		(pad "1" smd circle
			(at -0.40005 0 180)
			(size 0 0)
			(layers "F.Cu" "F.Mask" "F.Paste")
			(net "PVCCD_HV_CPU0_VCC")
		)
		(pad "2" smd circle
			(at 0.40005 0 180)
			(size 0 0)
			(layers "F.Cu" "F.Mask" "F.Paste")
			(net "GND")
		)
	)
	(footprint ""
		(layer "F.Cu")
		(at 377.300998 -75.74788 180)
		(property "Reference" "PL170"
			(at 8.649208 2.006092 0)
			(unlocked yes)
			(layer "F.SilkS")
			(effects
				(font
					(size 0.7874 0.5842)
					(thickness 0.1524)
				)
				(justify left)
			)
		)
		(property "Value" ""
			(at 0 0 180)
			(layer "F.Fab")
			(effects
				(font
					(size 1.27 1.27)
				)
			)
		)
		(duplicate_pad_numbers_are_jumpers no)
		(fp_line
			(start 3.64998 3.350006)
			(end -3.64998 3.350006)
			(stroke
				(width 0.1524)
				(type default)
			)
			(layer "F.SilkS")
		)
		(fp_line
			(start 3.64998 1.8034)
			(end 3.64998 3.350006)
			(stroke
				(width 0.1524)
				(type default)
			)
			(layer "F.SilkS")
		)
		(fp_line
			(start 3.64998 -3.350006)
			(end 3.64998 -1.8034)
			(stroke
				(width 0.1524)
				(type default)
			)
			(layer "F.SilkS")
		)
		(fp_line
			(start -3.64998 3.350006)
			(end -3.64998 1.8288)
			(stroke
				(width 0.1524)
				(type default)
			)
			(layer "F.SilkS")
		)
		(fp_line
			(start -3.64998 -1.8034)
			(end -3.64998 -3.350006)
			(stroke
				(width 0.1524)
				(type default)
			)
			(layer "F.SilkS")
		)
		(fp_line
			(start -3.6576 -3.350006)
			(end 3.64998 -3.350006)
			(stroke
				(width 0.1524)
				(type default)
			)
			(layer "F.SilkS")
		)
		(fp_line
			(start 3.64998 3.350006)
			(end -3.64998 3.350006)
			(stroke
				(width 0.1)
				(type default)
			)
			(layer "F.Fab")
		)
		(fp_line
			(start 3.64998 -3.350006)
			(end 3.64998 3.350006)
			(stroke
				(width 0.1)
				(type default)
			)
			(layer "F.Fab")
		)
		(fp_line
			(start -3.64998 3.350006)
			(end -3.64998 -3.350006)
			(stroke
				(width 0.1)
				(type default)
			)
			(layer "F.Fab")
		)
		(fp_line
			(start -3.64998 -3.350006)
			(end 3.64998 -3.350006)
			(stroke
				(width 0.1)
				(type default)
			)
			(layer "F.Fab")
		)
		(pad "1" smd rect
			(at -2.92481 0 180)
			(size 2.15392 3.302)
			(layers "F.Cu" "F.Mask" "F.Paste")
			(net "SW_P1V8_PCH_AUX_SW")
		)
		(pad "2" smd rect
			(at 2.92481 0 180)
			(size 2.15392 3.302)
			(layers "F.Cu" "F.Mask" "F.Paste")
			(net "P1V8_PCH_AUX")
		)
	)
	(footprint ""
		(layer "F.Cu")
		(at 102.844346 -357.562658)
		(property "Reference" "R310"
			(at 0 0 0)
			(layer "F.SilkS")
			(hide yes)
			(effects
				(font
					(size 1.27 1.27)
				)
			)
		)
		(property "Value" ""
			(at 0 0 0)
			(layer "F.Fab")
			(effects
				(font
					(size 1.27 1.27)
				)
			)
		)
		(duplicate_pad_numbers_are_jumpers no)
		(fp_line
			(start -0.7874 -0.4064)
			(end 0.7874 -0.4064)
			(stroke
				(width 0.1524)
				(type default)
			)
			(layer "F.SilkS")
		)
		(fp_line
			(start -0.7874 0.4064)
			(end -0.7874 -0.4064)
			(stroke
				(width 0.1524)
				(type default)
			)
			(layer "F.SilkS")
		)
		(fp_line
			(start 0.7874 -0.4064)
			(end 0.7874 0.4064)
			(stroke
				(width 0.1524)
				(type default)
			)
			(layer "F.SilkS")
		)
		(fp_line
			(start 0.7874 0.4064)
			(end -0.7874 0.4064)
			(stroke
				(width 0.1524)
				(type default)
			)
			(layer "F.SilkS")
		)
		(fp_line
			(start -0.67945 -0.305054)
			(end -0.12065 -0.305054)
			(stroke
				(width 0.1)
				(type default)
			)
			(layer "F.Fab")
		)
		(fp_line
			(start -0.67945 0.3048)
			(end -0.67945 -0.305054)
			(stroke
				(width 0.1)
				(type default)
			)
			(layer "F.Fab")
		)
		(fp_line
			(start -0.12065 -0.305054)
			(end -0.12065 -0.2794)
			(stroke
				(width 0.1)
				(type default)
			)
			(layer "F.Fab")
		)
		(fp_line
			(start -0.12065 -0.2794)
			(end 0.12065 -0.2794)
			(stroke
				(width 0.1)
				(type default)
			)
			(layer "F.Fab")
		)
		(fp_line
			(start -0.12065 0.2794)
			(end -0.12065 0.3048)
			(stroke
				(width 0.1)
				(type default)
			)
			(layer "F.Fab")
		)
		(fp_line
			(start -0.12065 0.3048)
			(end -0.67945 0.3048)
			(stroke
				(width 0.1)
				(type default)
			)
			(layer "F.Fab")
		)
		(fp_line
			(start 0.120396 0.2794)
			(end -0.12065 0.2794)
			(stroke
				(width 0.1)
				(type default)
			)
			(layer "F.Fab")
		)
		(fp_line
			(start 0.120396 0.3048)
			(end 0.120396 0.2794)
			(stroke
				(width 0.1)
				(type default)
			)
			(layer "F.Fab")
		)
		(fp_line
			(start 0.12065 -0.3048)
			(end 0.67945 -0.3048)
			(stroke
				(width 0.1)
				(type default)
			)
			(layer "F.Fab")
		)
		(fp_line
			(start 0.12065 -0.2794)
			(end 0.12065 -0.3048)
			(stroke
				(width 0.1)
				(type default)
			)
			(layer "F.Fab")
		)
		(fp_line
			(start 0.67945 -0.3048)
			(end 0.67945 0.3048)
			(stroke
				(width 0.1)
				(type default)
			)
			(layer "F.Fab")
		)
		(fp_line
			(start 0.67945 0.3048)
			(end 0.120396 0.3048)
			(stroke
				(width 0.1)
				(type default)
			)
			(layer "F.Fab")
		)
		(pad "1" smd circle
			(at -0.40005 0)
			(size 0 0)
			(layers "F.Cu" "F.Mask" "F.Paste")
			(net "SVID_CLK0_CPU1_R")
		)
		(pad "2" smd circle
			(at 0.40005 0)
			(size 0 0)
			(layers "F.Cu" "F.Mask" "F.Paste")
			(net "SVID_CLK_PVCCIN_CPU1_R")
		)
	)
)
